# BASEBOARD_FAB2 (Tioga Pass) — schematic netlist excerpt (pin names and nets, part order shuffled) for the footprints in the layout excerpt that follows; sources: Cadence DE-HDL packaged netlist, KiCad conversion of Wiwynn_Tioga_Pass_MB.brd

R1W25  RES  1.00K 1% CHIP  pkg 0402  page 101 : A = PU_33P_33M_SMBADR ; B = GND

Q4B1  FET_N_DUAL  NTJD4001N FET  pkg SMLF  page 94
  SOURCE(0)  = GND
  GATE(0)  = IRQ_PVDDQ_KLM_VRHOT_LVT3_N
  DRAIN(0)  = H_CPU1_MEMKLM_MEMHOT_G_N
  SOURCE(0)  = GND
  GATE(0)  = H_CPU1_MEMKLM_MEMHOT
  DRAIN(0)  = H_CPU1_MEMKLM_MEMHOT

(kicad_pcb
	(version 20260206)
	(generator "pcbnew")
	(generator_version "10.0")
	(general
		(thickness 1.6)
		(legacy_teardrops no)
	)
	(paper "A4")
	(title_block
		(title "Wiwynn_Tioga_Pass_MB.brd")
		(comment 1 "Tioga Pass / footprints 1917-1918 of 4770")
	)
	(layers
		(0 "F.Cu" signal "TOP")
		(4 "In1.Cu" signal "L2GND")
		(6 "In2.Cu" signal "L3")
		(8 "In3.Cu" signal "L4GND")
		(10 "In4.Cu" signal "L5")
		(12 "In5.Cu" signal "L6GND")
		(14 "In6.Cu" signal "L7VCC")
		(16 "In7.Cu" signal "L8VCC")
		(18 "In8.Cu" signal "L9GND")
		(20 "In9.Cu" signal "L10")
		(22 "In10.Cu" signal "L11GND")
		(24 "In11.Cu" signal "L12")
		(26 "In12.Cu" signal "L13GND")
		(2 "B.Cu" signal "BOTTOM")
		(9 "F.Adhes" user "F.Adhesive")
		(11 "B.Adhes" user "B.Adhesive")
		(13 "F.Paste" user "Package Geometry/Pastemask Top")
		(15 "B.Paste" user "Package Geometry/Pastemask Bottom")
		(5 "F.SilkS" user "Ref Des/Silkscreen Top")
		(7 "B.SilkS" user "Ref Des/Silkscreen Bottom")
		(1 "F.Mask" user "Board Geometry/Soldermask Top")
		(3 "B.Mask" user "Board Geometry/Soldermask Bottom")
		(17 "Dwgs.User" user "User.Drawings")
		(19 "Cmts.User" user "User.Comments")
		(21 "Eco1.User" user "User.Eco1")
		(23 "Eco2.User" user "User.Eco2")
		(25 "Edge.Cuts" user "Board Geometry/Outline")
		(27 "Margin" user)
		(31 "F.CrtYd" user "Package Geometry/Place Bound Top")
		(29 "B.CrtYd" user "Package Geometry/Place Bound Bottom")
		(35 "F.Fab" user "Ref Des/Assembly Top")
		(33 "B.Fab" user "Ref Des/Assembly Bottom")
	)
	(footprint ""
		(layer "F.Cu")
		(at 173.8757 -126.99238 -90)
		(property "Reference" "Q4B1"
			(at 2.27838 2.98323 90)
			(unlocked yes)
			(layer "F.SilkS")
			(effects
				(font
					(size 0.7874 0.5842)
					(thickness 0.1524)
				)
				(justify left)
			)
		)
		(property "Value" ""
			(at 0 0 270)
			(layer "F.Fab")
			(effects
				(font
					(size 1.27 1.27)
				)
			)
		)
		(duplicate_pad_numbers_are_jumpers no)
		(fp_circle
			(center -0.508 -0.7874)
			(end -0.508 -0.9144)
			(stroke
				(width 0.254)
				(type default)
			)
			(fill no)
			(layer "F.SilkS")
		)
		(fp_poly
			(pts
				(xy 0.2159 1.7526) (xy 1.5621 1.7526) (xy 1.5621 -0.4572) (xy 0.2159 -0.4572)
			)
			(stroke
				(width 0)
				(type default)
			)
			(fill no)
			(layer "F.CrtYd")
		)
		(fp_line
			(start 0.2159 1.75514)
			(end 1.5621 1.75514)
			(stroke
				(width 0.1)
				(type default)
			)
			(layer "F.Fab")
		)
		(fp_line
			(start 1.5621 1.75514)
			(end 1.5621 -0.45466)
			(stroke
				(width 0.1)
				(type default)
			)
			(layer "F.Fab")
		)
		(fp_line
			(start 0.2159 -0.45466)
			(end 0.2159 1.75514)
			(stroke
				(width 0.1)
				(type default)
			)
			(layer "F.Fab")
		)
		(fp_line
			(start 1.5621 -0.45466)
			(end 0.2159 -0.45466)
			(stroke
				(width 0.1)
				(type default)
			)
			(layer "F.Fab")
		)
		(fp_circle
			(center -0.508 -0.7874)
			(end -0.508 -0.9144)
			(stroke
				(width 0.254)
				(type default)
			)
			(fill no)
			(layer "F.Fab")
		)
		(pad "1" smd rect
			(at 0 0 270)
			(size 1.016 0.381)
			(layers "F.Cu" "F.Mask" "F.Paste")
			(net "GND")
		)
		(pad "2" smd rect
			(at 0 0.65024 270)
			(size 1.016 0.381)
			(layers "F.Cu" "F.Mask" "F.Paste")
			(net "IRQ_PVDDQ_KLM_VRHOT_LVT3_N")
		)
		(pad "3" smd rect
			(at 0 1.30048 270)
			(size 1.016 0.381)
			(layers "F.Cu" "F.Mask" "F.Paste")
			(net "H_CPU1_MEMKLM_MEMHOT_G_N")
		)
		(pad "4" smd rect
			(at 1.778 1.30048 270)
			(size 1.016 0.381)
			(layers "F.Cu" "F.Mask" "F.Paste")
			(net "GND")
		)
		(pad "5" smd rect
			(at 1.778 0.65024 270)
			(size 1.016 0.381)
			(layers "F.Cu" "F.Mask" "F.Paste")
			(net "H_CPU1_MEMKLM_MEMHOT")
		)
		(pad "6" smd rect
			(at 1.778 0 270)
			(size 1.016 0.381)
			(layers "F.Cu" "F.Mask" "F.Paste")
			(net "H_CPU1_MEMKLM_MEMHOT")
		)
		(zone
			(layer "F.Cu")
			(hatch none 0.5)
			(connect_pads
				(clearance 0)
			)
			(min_thickness 0.25)
			(keepout
				(tracks allowed)
				(vias not_allowed)
				(pads allowed)
				(copperpour not_allowed)
				(footprints allowed)
			)
			(placement
				(enabled no)
				(sheetname "")
			)
			(fill
				(thermal_gap 0.5)
				(thermal_bridge_width 0.5)
				(island_removal_mode 0)
			)
			(polygon
				(pts
					(xy 174.0662 -127.50038) (xy 174.0662 -126.48438) (xy 172.3771 -126.48438) (xy 172.3771 -127.50038)
				)
			)
		)
		(zone
			(layer "F.Cu")
			(hatch none 0.5)
			(connect_pads
				(clearance 0)
			)
			(min_thickness 0.25)
			(keepout
				(tracks allowed)
				(vias not_allowed)
				(pads allowed)
				(copperpour not_allowed)
				(footprints allowed)
			)
			(placement
				(enabled no)
				(sheetname "")
			)
			(fill
				(thermal_gap 0.5)
				(thermal_bridge_width 0.5)
				(island_removal_mode 0)
			)
			(polygon
				(pts
					(xy 174.0662 -125.72238) (xy 174.0662 -124.70638) (xy 172.3771 -124.70638) (xy 172.3771 -125.72238)
				)
			)
		)
	)
	(footprint ""
		(layer "F.Cu")
		(at 479.77298 -35.5854 90)
		(property "Reference" "R1W25"
			(at -0.8382 -0.67818 90)
			(unlocked yes)
			(layer "F.SilkS")
			(effects
				(font
					(size 0.4064 0.254)
					(thickness 0.1524)
				)
				(justify left)
			)
		)
		(property "Value" ""
			(at 0 0 90)
			(layer "F.Fab")
			(effects
				(font
					(size 1.27 1.27)
				)
			)
		)
		(duplicate_pad_numbers_are_jumpers no)
		(fp_poly
			(pts
				(xy -0.2794 -0.1016) (xy 0.2794 -0.1016) (xy 0.2794 0.9906) (xy -0.2794 0.9906)
			)
			(stroke
				(width 0)
				(type default)
			)
			(fill no)
			(layer "F.CrtYd")
		)
		(fp_line
			(start 0.2794 -0.1016)
			(end -0.2794 -0.1016)
			(stroke
				(width 0.1)
				(type default)
			)
			(layer "F.Fab")
		)
		(fp_line
			(start -0.2794 -0.1016)
			(end -0.2794 0.9906)
			(stroke
				(width 0.1)
				(type default)
			)
			(layer "F.Fab")
		)
		(fp_line
			(start 0.2794 0.9906)
			(end 0.2794 -0.1016)
			(stroke
				(width 0.1)
				(type default)
			)
			(layer "F.Fab")
		)
		(fp_line
			(start -0.2794 0.9906)
			(end 0.2794 0.9906)
			(stroke
				(width 0.1)
				(type default)
			)
			(layer "F.Fab")
		)
		(pad "1" smd rect
			(at 0 0 90)
			(size 0.508 0.508)
			(layers "F.Cu" "F.Mask" "F.Paste")
			(net "PU_33P_33M_SMBADR")
		)
		(pad "2" smd rect
			(at 0 0.889 90)
			(size 0.508 0.508)
			(layers "F.Cu" "F.Mask" "F.Paste")
			(net "GND")
		)
		(zone
			(layer "F.Cu")
			(hatch none 0.5)
			(connect_pads
				(clearance 0)
			)
			(min_thickness 0.25)
			(keepout
				(tracks allowed)
				(vias not_allowed)
				(pads allowed)
				(copperpour not_allowed)
				(footprints allowed)
			)
			(placement
				(enabled no)
				(sheetname "")
			)
			(fill
				(thermal_gap 0.5)
				(thermal_bridge_width 0.5)
				(island_removal_mode 0)
			)
			(polygon
				(pts
					(xy 480.02698 -35.3314) (xy 480.02698 -35.8394) (xy 480.40798 -35.8394) (xy 480.40798 -35.3314)
				)
			)
		)
		(zone
			(layer "F.Cu")
			(hatch none 0.5)
			(connect_pads
				(clearance 0)
			)
			(min_thickness 0.25)
			(keepout
				(tracks not_allowed)
				(vias allowed)
				(pads allowed)
				(copperpour not_allowed)
				(footprints allowed)
			)
			(placement
				(enabled no)
				(sheetname "")
			)
			(fill
				(thermal_gap 0.5)
				(thermal_bridge_width 0.5)
				(island_removal_mode 0)
			)
			(polygon
				(pts
					(xy 480.40798 -35.3314) (xy 480.40798 -35.8394) (xy 480.02698 -35.8394) (xy 480.02698 -35.3314)
				)
			)
		)
	)
)
